(kicad_pcb
	(version 20260206)
	(generator "pcbnew")
	(generator_version "10.0")
	(general
		(thickness 1.6)
		(legacy_teardrops no)
	)
	(paper "A4")
	(title_block
		(title "01162023_DA0F0TEBIF0_F0T_Expander_BD_F_brd_V02_OCP.brd")
		(comment 1 "Grand Teton / footprints 4867-4871 of 9728")
	)
	(layers
		(0 "F.Cu" signal "TOP")
		(4 "In1.Cu" signal "GND")
		(6 "In2.Cu" signal "VCC")
		(8 "In3.Cu" signal "VCC1")
		(10 "In4.Cu" signal "GND1")
		(12 "In5.Cu" signal "IN1")
		(14 "In6.Cu" signal "GND2")
		(16 "In7.Cu" signal "IN2")
		(18 "In8.Cu" signal "GND3")
		(20 "In9.Cu" signal "IN3")
		(22 "In10.Cu" signal "GND4")
		(24 "In11.Cu" signal "IN4")
		(26 "In12.Cu" signal "GND5")
		(28 "In13.Cu" signal "IN5")
		(30 "In14.Cu" signal "GND6")
		(32 "In15.Cu" signal "IN6")
		(34 "In16.Cu" signal "GND7")
		(2 "B.Cu" signal "BOTTOM")
		(9 "F.Adhes" user "F.Adhesive")
		(11 "B.Adhes" user "B.Adhesive")
		(13 "F.Paste" user "Package Geometry/Pastemask Top")
		(15 "B.Paste" user "Package Geometry/Pastemask Bottom")
		(5 "F.SilkS" user "Ref Des/Silkscreen Top")
		(7 "B.SilkS" user "Ref Des/Silkscreen Bottom")
		(1 "F.Mask" user "Board Geometry/Soldermask Top")
		(3 "B.Mask" user "Board Geometry/Soldermask Bottom")
		(17 "Dwgs.User" user "User.Drawings")
		(19 "Cmts.User" user "User.Comments")
		(21 "Eco1.User" user "User.Eco1")
		(23 "Eco2.User" user "User.Eco2")
		(25 "Edge.Cuts" user "Board Geometry/Outline")
		(27 "Margin" user)
		(31 "F.CrtYd" user "Package Geometry/Place Bound Top")
		(29 "B.CrtYd" user "Package Geometry/Place Bound Bottom")
		(35 "F.Fab" user "Ref Des/Assembly Top")
		(33 "B.Fab" user "Ref Des/Assembly Bottom")
	)
	(footprint ""
		(layer "F.Cu")
		(at 226.819714 -173.838362 180)
		(property "Reference" "D23"
			(at 1.826514 -1.424432 0)
			(unlocked yes)
			(layer "F.SilkS")
			(effects
				(font
					(size 0.7874 0.5842)
					(thickness 0.1524)
				)
				(justify left)
			)
		)
		(property "Value" ""
			(at 0 0 180)
			(layer "F.Fab")
			(effects
				(font
					(size 1.27 1.27)
				)
			)
		)
		(duplicate_pad_numbers_are_jumpers no)
		(fp_line
			(start 2.032 0.7112)
			(end -1.651 0.7112)
			(stroke
				(width 0.1524)
				(type default)
			)
			(layer "F.SilkS")
		)
		(fp_line
			(start 2.032 -0.7112)
			(end 2.032 0.7112)
			(stroke
				(width 0.1524)
				(type default)
			)
			(layer "F.SilkS")
		)
		(fp_line
			(start 1.905 -0.6858)
			(end 1.905 0.6858)
			(stroke
				(width 0.1524)
				(type default)
			)
			(layer "F.SilkS")
		)
		(fp_line
			(start 1.778 0.6858)
			(end 1.778 -0.6858)
			(stroke
				(width 0.1524)
				(type default)
			)
			(layer "F.SilkS")
		)
		(fp_line
			(start 1.651 -0.6858)
			(end 1.651 0.6858)
			(stroke
				(width 0.1524)
				(type default)
			)
			(layer "F.SilkS")
		)
		(fp_line
			(start 0.299974 -0.500126)
			(end 0.299974 0.500126)
			(stroke
				(width 0.1524)
				(type default)
			)
			(layer "F.SilkS")
		)
		(fp_line
			(start 0.199898 0)
			(end -0.299974 -0.500126)
			(stroke
				(width 0.1524)
				(type default)
			)
			(layer "F.SilkS")
		)
		(fp_line
			(start -0.299974 0.500126)
			(end 0.199898 0)
			(stroke
				(width 0.1524)
				(type default)
			)
			(layer "F.SilkS")
		)
		(fp_line
			(start -0.299974 -0.500126)
			(end -0.299974 0.500126)
			(stroke
				(width 0.1524)
				(type default)
			)
			(layer "F.SilkS")
		)
		(fp_line
			(start -1.651 0.7112)
			(end -1.651 -0.7112)
			(stroke
				(width 0.1524)
				(type default)
			)
			(layer "F.SilkS")
		)
		(fp_line
			(start -1.651 -0.7112)
			(end 2.032 -0.7112)
			(stroke
				(width 0.1524)
				(type default)
			)
			(layer "F.SilkS")
		)
		(fp_line
			(start 1.35001 0.175006)
			(end 0.899922 0.175006)
			(stroke
				(width 0.1)
				(type default)
			)
			(layer "F.Fab")
		)
		(fp_line
			(start 1.35001 -0.225044)
			(end 1.35001 0.175006)
			(stroke
				(width 0.1)
				(type default)
			)
			(layer "F.Fab")
		)
		(fp_line
			(start 0.899922 0.700024)
			(end -0.899922 0.700024)
			(stroke
				(width 0.1)
				(type default)
			)
			(layer "F.Fab")
		)
		(fp_line
			(start 0.899922 0.175006)
			(end 0.899922 0.700024)
			(stroke
				(width 0.1)
				(type default)
			)
			(layer "F.Fab")
		)
		(fp_line
			(start 0.899922 -0.225044)
			(end 1.35001 -0.225044)
			(stroke
				(width 0.1)
				(type default)
			)
			(layer "F.Fab")
		)
		(fp_line
			(start 0.899922 -0.700024)
			(end 0.899922 -0.225044)
			(stroke
				(width 0.1)
				(type default)
			)
			(layer "F.Fab")
		)
		(fp_line
			(start 0.299974 -0.500126)
			(end 0.299974 0.500126)
			(stroke
				(width 0.1)
				(type default)
			)
			(layer "F.Fab")
		)
		(fp_line
			(start 0.199898 0)
			(end -0.299974 -0.500126)
			(stroke
				(width 0.1)
				(type default)
			)
			(layer "F.Fab")
		)
		(fp_line
			(start -0.299974 0.500126)
			(end 0.199898 0)
			(stroke
				(width 0.1)
				(type default)
			)
			(layer "F.Fab")
		)
		(fp_line
			(start -0.299974 -0.500126)
			(end -0.299974 0.500126)
			(stroke
				(width 0.1)
				(type default)
			)
			(layer "F.Fab")
		)
		(fp_line
			(start -0.899922 0.700024)
			(end -0.899922 0.175006)
			(stroke
				(width 0.1)
				(type default)
			)
			(layer "F.Fab")
		)
		(fp_line
			(start -0.899922 0.175006)
			(end -1.35001 0.175006)
			(stroke
				(width 0.1)
				(type default)
			)
			(layer "F.Fab")
		)
		(fp_line
			(start -0.899922 -0.225044)
			(end -0.899922 -0.700024)
			(stroke
				(width 0.1)
				(type default)
			)
			(layer "F.Fab")
		)
		(fp_line
			(start -0.899922 -0.700024)
			(end 0.899922 -0.700024)
			(stroke
				(width 0.1)
				(type default)
			)
			(layer "F.Fab")
		)
		(fp_line
			(start -1.35001 0.175006)
			(end -1.35001 -0.225044)
			(stroke
				(width 0.1)
				(type default)
			)
			(layer "F.Fab")
		)
		(fp_line
			(start -1.35001 -0.225044)
			(end -0.899922 -0.225044)
			(stroke
				(width 0.1)
				(type default)
			)
			(layer "F.Fab")
		)
		(fp_text user "-"
			(at 2.261616 -2.594102 180)
			(unlocked yes)
			(layer "F.SilkS")
			(effects
				(font
					(size 1.905 1.4224)
					(thickness 0.1524)
				)
				(justify left)
			)
		)
		(fp_text user "+"
			(at -2.794 -0.19685 180)
			(unlocked yes)
			(layer "F.SilkS")
			(effects
				(font
					(size 1.905 1.4224)
					(thickness 0.1524)
				)
				(justify left)
			)
		)
		(fp_text user "-"
			(at 1.8288 -0.24765 180)
			(unlocked yes)
			(layer "F.Fab")
			(effects
				(font
					(size 1.905 1.4224)
					(thickness 0.1524)
				)
				(justify left)
			)
		)
		(fp_text user "+"
			(at -2.794 -0.19685 180)
			(unlocked yes)
			(layer "F.Fab")
			(effects
				(font
					(size 1.905 1.4224)
					(thickness 0.1524)
				)
				(justify left)
			)
		)
		(pad "1" smd rect
			(at -1.0922 0)
			(size 0.8128 0.8636)
			(layers "F.Cu" "F.Mask" "F.Paste")
			(net "ADM1085_ENOUT")
		)
		(pad "2" smd rect
			(at 1.0922 0 180)
			(size 0.8128 0.8636)
			(layers "F.Cu" "F.Mask" "F.Paste")
			(net "ADM1085_CEXT")
		)
	)
	(footprint ""
		(layer "F.Cu")
		(at 374.567196 -57.332626)
		(property "Reference" "R6829"
			(at 0 0 0)
			(layer "F.SilkS")
			(hide yes)
			(effects
				(font
					(size 1.27 1.27)
				)
			)
		)
		(property "Value" ""
			(at 0 0 0)
			(layer "F.Fab")
			(effects
				(font
					(size 1.27 1.27)
				)
			)
		)
		(duplicate_pad_numbers_are_jumpers no)
		(fp_line
			(start -0.7874 -0.4064)
			(end 0.7874 -0.4064)
			(stroke
				(width 0.1524)
				(type default)
			)
			(layer "F.SilkS")
		)
		(fp_line
			(start -0.7874 0.4064)
			(end -0.7874 -0.4064)
			(stroke
				(width 0.1524)
				(type default)
			)
			(layer "F.SilkS")
		)
		(fp_line
			(start 0.7874 -0.4064)
			(end 0.7874 0.4064)
			(stroke
				(width 0.1524)
				(type default)
			)
			(layer "F.SilkS")
		)
		(fp_line
			(start 0.7874 0.4064)
			(end -0.7874 0.4064)
			(stroke
				(width 0.1524)
				(type default)
			)
			(layer "F.SilkS")
		)
		(fp_line
			(start -0.67945 -0.305054)
			(end -0.12065 -0.305054)
			(stroke
				(width 0.1)
				(type default)
			)
			(layer "F.Fab")
		)
		(fp_line
			(start -0.67945 0.3048)
			(end -0.67945 -0.305054)
			(stroke
				(width 0.1)
				(type default)
			)
			(layer "F.Fab")
		)
		(fp_line
			(start -0.12065 -0.305054)
			(end -0.12065 -0.2794)
			(stroke
				(width 0.1)
				(type default)
			)
			(layer "F.Fab")
		)
		(fp_line
			(start -0.12065 -0.2794)
			(end 0.12065 -0.2794)
			(stroke
				(width 0.1)
				(type default)
			)
			(layer "F.Fab")
		)
		(fp_line
			(start -0.12065 0.2794)
			(end -0.12065 0.3048)
			(stroke
				(width 0.1)
				(type default)
			)
			(layer "F.Fab")
		)
		(fp_line
			(start -0.12065 0.3048)
			(end -0.67945 0.3048)
			(stroke
				(width 0.1)
				(type default)
			)
			(layer "F.Fab")
		)
		(fp_line
			(start 0.120396 0.2794)
			(end -0.12065 0.2794)
			(stroke
				(width 0.1)
				(type default)
			)
			(layer "F.Fab")
		)
		(fp_line
			(start 0.120396 0.3048)
			(end 0.120396 0.2794)
			(stroke
				(width 0.1)
				(type default)
			)
			(layer "F.Fab")
		)
		(fp_line
			(start 0.12065 -0.3048)
			(end 0.67945 -0.3048)
			(stroke
				(width 0.1)
				(type default)
			)
			(layer "F.Fab")
		)
		(fp_line
			(start 0.12065 -0.2794)
			(end 0.12065 -0.3048)
			(stroke
				(width 0.1)
				(type default)
			)
			(layer "F.Fab")
		)
		(fp_line
			(start 0.67945 -0.3048)
			(end 0.67945 0.3048)
			(stroke
				(width 0.1)
				(type default)
			)
			(layer "F.Fab")
		)
		(fp_line
			(start 0.67945 0.3048)
			(end 0.120396 0.3048)
			(stroke
				(width 0.1)
				(type default)
			)
			(layer "F.Fab")
		)
		(pad "1" smd circle
			(at -0.40005 0)
			(size 0 0)
			(layers "F.Cu" "F.Mask" "F.Paste")
			(net "SSD12_PWR_EN_R")
		)
		(pad "2" smd circle
			(at 0.40005 0)
			(size 0 0)
			(layers "F.Cu" "F.Mask" "F.Paste")
			(net "GND")
		)
	)
	(footprint ""
		(layer "F.Cu")
		(at 302.126396 -25.432004 -90)
		(property "Reference" "C975"
			(at 0 0 270)
			(layer "F.SilkS")
			(hide yes)
			(effects
				(font
					(size 1.27 1.27)
				)
			)
		)
		(property "Value" ""
			(at 0 0 270)
			(layer "F.Fab")
			(effects
				(font
					(size 1.27 1.27)
				)
			)
		)
		(duplicate_pad_numbers_are_jumpers no)
		(fp_line
			(start -0.7874 0.4064)
			(end -0.7874 -0.4064)
			(stroke
				(width 0.1524)
				(type default)
			)
			(layer "F.SilkS")
		)
		(fp_line
			(start 0.7874 0.4064)
			(end -0.7874 0.4064)
			(stroke
				(width 0.1524)
				(type default)
			)
			(layer "F.SilkS")
		)
		(fp_line
			(start -0.7874 -0.4064)
			(end 0.7874 -0.4064)
			(stroke
				(width 0.1524)
				(type default)
			)
			(layer "F.SilkS")
		)
		(fp_line
			(start 0.7874 -0.4064)
			(end 0.7874 0.4064)
			(stroke
				(width 0.1524)
				(type default)
			)
			(layer "F.SilkS")
		)
		(fp_line
			(start -0.67945 0.3048)
			(end -0.67945 -0.305054)
			(stroke
				(width 0.1)
				(type default)
			)
			(layer "F.Fab")
		)
		(fp_line
			(start -0.12065 0.3048)
			(end -0.67945 0.3048)
			(stroke
				(width 0.1)
				(type default)
			)
			(layer "F.Fab")
		)
		(fp_line
			(start 0.120396 0.3048)
			(end 0.120396 0.2794)
			(stroke
				(width 0.1)
				(type default)
			)
			(layer "F.Fab")
		)
		(fp_line
			(start 0.67945 0.3048)
			(end 0.120396 0.3048)
			(stroke
				(width 0.1)
				(type default)
			)
			(layer "F.Fab")
		)
		(fp_line
			(start -0.12065 0.2794)
			(end -0.12065 0.3048)
			(stroke
				(width 0.1)
				(type default)
			)
			(layer "F.Fab")
		)
		(fp_line
			(start 0.120396 0.2794)
			(end -0.12065 0.2794)
			(stroke
				(width 0.1)
				(type default)
			)
			(layer "F.Fab")
		)
		(fp_line
			(start -0.12065 -0.2794)
			(end 0.12065 -0.2794)
			(stroke
				(width 0.1)
				(type default)
			)
			(layer "F.Fab")
		)
		(fp_line
			(start 0.12065 -0.2794)
			(end 0.12065 -0.3048)
			(stroke
				(width 0.1)
				(type default)
			)
			(layer "F.Fab")
		)
		(fp_line
			(start 0.12065 -0.3048)
			(end 0.67945 -0.3048)
			(stroke
				(width 0.1)
				(type default)
			)
			(layer "F.Fab")
		)
		(fp_line
			(start 0.67945 -0.3048)
			(end 0.67945 0.3048)
			(stroke
				(width 0.1)
				(type default)
			)
			(layer "F.Fab")
		)
		(fp_line
			(start -0.67945 -0.305054)
			(end -0.12065 -0.305054)
			(stroke
				(width 0.1)
				(type default)
			)
			(layer "F.Fab")
		)
		(fp_line
			(start -0.12065 -0.305054)
			(end -0.12065 -0.2794)
			(stroke
				(width 0.1)
				(type default)
			)
			(layer "F.Fab")
		)
		(pad "1" smd circle
			(at -0.40005 0 270)
			(size 0 0)
			(layers "F.Cu" "F.Mask" "F.Paste")
			(net "GND")
		)
		(pad "2" smd circle
			(at 0.40005 0 270)
			(size 0 0)
			(layers "F.Cu" "F.Mask" "F.Paste")
			(net "P3V3_SSD10")
		)
	)
	(footprint ""
		(layer "F.Cu")
		(at 208.45272 -311.197244 135)
		(property "Reference" "R1313"
			(at 0 0 135)
			(layer "F.SilkS")
			(hide yes)
			(effects
				(font
					(size 1.27 1.27)
				)
			)
		)
		(property "Value" ""
			(at 0 0 135)
			(layer "F.Fab")
			(effects
				(font
					(size 1.27 1.27)
				)
			)
		)
		(duplicate_pad_numbers_are_jumpers no)
		(fp_line
			(start 0.787389 -0.406267)
			(end 0.787389 0.406267)
			(stroke
				(width 0.1524)
				(type default)
			)
			(layer "F.SilkS")
		)
		(fp_line
			(start 0.787389 0.406267)
			(end -0.787389 0.406267)
			(stroke
				(width 0.1524)
				(type default)
			)
			(layer "F.SilkS")
		)
		(fp_line
			(start -0.787389 -0.406267)
			(end 0.787389 -0.406267)
			(stroke
				(width 0.1524)
				(type default)
			)
			(layer "F.SilkS")
		)
		(fp_line
			(start -0.787389 0.406267)
			(end -0.787389 -0.406267)
			(stroke
				(width 0.1524)
				(type default)
			)
			(layer "F.SilkS")
		)
		(fp_line
			(start 0.679446 -0.30479)
			(end 0.679446 0.30479)
			(stroke
				(width 0.1)
				(type default)
			)
			(layer "F.Fab")
		)
		(fp_line
			(start 0.120515 -0.30479)
			(end 0.679446 -0.30479)
			(stroke
				(width 0.1)
				(type default)
			)
			(layer "F.Fab")
		)
		(fp_line
			(start 0.120695 -0.279466)
			(end 0.120515 -0.30479)
			(stroke
				(width 0.1)
				(type default)
			)
			(layer "F.Fab")
		)
		(fp_line
			(start 0.679446 0.30479)
			(end 0.120515 0.30479)
			(stroke
				(width 0.1)
				(type default)
			)
			(layer "F.Fab")
		)
		(fp_line
			(start -0.120695 -0.304969)
			(end -0.120695 -0.279466)
			(stroke
				(width 0.1)
				(type default)
			)
			(layer "F.Fab")
		)
		(fp_line
			(start -0.120695 -0.279466)
			(end 0.120695 -0.279466)
			(stroke
				(width 0.1)
				(type default)
			)
			(layer "F.Fab")
		)
		(fp_line
			(start 0.120335 0.279466)
			(end -0.120695 0.279466)
			(stroke
				(width 0.1)
				(type default)
			)
			(layer "F.Fab")
		)
		(fp_line
			(start 0.120515 0.30479)
			(end 0.120335 0.279466)
			(stroke
				(width 0.1)
				(type default)
			)
			(layer "F.Fab")
		)
		(fp_line
			(start -0.679446 -0.305149)
			(end -0.120695 -0.304969)
			(stroke
				(width 0.1)
				(type default)
			)
			(layer "F.Fab")
		)
		(fp_line
			(start -0.120695 0.279466)
			(end -0.120515 0.30479)
			(stroke
				(width 0.1)
				(type default)
			)
			(layer "F.Fab")
		)
		(fp_line
			(start -0.120515 0.30479)
			(end -0.679446 0.30479)
			(stroke
				(width 0.1)
				(type default)
			)
			(layer "F.Fab")
		)
		(fp_line
			(start -0.679446 0.30479)
			(end -0.679446 -0.305149)
			(stroke
				(width 0.1)
				(type default)
			)
			(layer "F.Fab")
		)
		(pad "1" smd circle
			(at -0.40005 0 135)
			(size 0 0)
			(layers "F.Cu" "F.Mask" "F.Paste")
			(net "GND")
		)
		(pad "2" smd circle
			(at 0.40005 0 135)
			(size 0 0)
			(layers "F.Cu" "F.Mask" "F.Paste")
			(net "PEX1_SPARE5")
		)
	)
	(footprint ""
		(layer "F.Cu")
		(at 38.7604 -117.7544 180)
		(property "Reference" "R5"
			(at 0 0 180)
			(layer "F.SilkS")
			(hide yes)
			(effects
				(font
					(size 1.27 1.27)
				)
			)
		)
		(property "Value" ""
			(at 0 0 180)
			(layer "F.Fab")
			(effects
				(font
					(size 1.27 1.27)
				)
			)
		)
		(duplicate_pad_numbers_are_jumpers no)
		(fp_line
			(start 0.7874 0.4064)
			(end -0.7874 0.4064)
			(stroke
				(width 0.1524)
				(type default)
			)
			(layer "F.SilkS")
		)
		(fp_line
			(start 0.7874 -0.4064)
			(end 0.7874 0.4064)
			(stroke
				(width 0.1524)
				(type default)
			)
			(layer "F.SilkS")
		)
		(fp_line
			(start -0.7874 0.4064)
			(end -0.7874 -0.4064)
			(stroke
				(width 0.1524)
				(type default)
			)
			(layer "F.SilkS")
		)
		(fp_line
			(start -0.7874 -0.4064)
			(end 0.7874 -0.4064)
			(stroke
				(width 0.1524)
				(type default)
			)
			(layer "F.SilkS")
		)
		(fp_line
			(start 0.67945 0.3048)
			(end 0.120396 0.3048)
			(stroke
				(width 0.1)
				(type default)
			)
			(layer "F.Fab")
		)
		(fp_line
			(start 0.67945 -0.3048)
			(end 0.67945 0.3048)
			(stroke
				(width 0.1)
				(type default)
			)
			(layer "F.Fab")
		)
		(fp_line
			(start 0.12065 -0.2794)
			(end 0.12065 -0.3048)
			(stroke
				(width 0.1)
				(type default)
			)
			(layer "F.Fab")
		)
		(fp_line
			(start 0.12065 -0.3048)
			(end 0.67945 -0.3048)
			(stroke
				(width 0.1)
				(type default)
			)
			(layer "F.Fab")
		)
		(fp_line
			(start 0.120396 0.3048)
			(end 0.120396 0.2794)
			(stroke
				(width 0.1)
				(type default)
			)
			(layer "F.Fab")
		)
		(fp_line
			(start 0.120396 0.2794)
			(end -0.12065 0.2794)
			(stroke
				(width 0.1)
				(type default)
			)
			(layer "F.Fab")
		)
		(fp_line
			(start -0.12065 0.3048)
			(end -0.67945 0.3048)
			(stroke
				(width 0.1)
				(type default)
			)
			(layer "F.Fab")
		)
		(fp_line
			(start -0.12065 0.2794)
			(end -0.12065 0.3048)
			(stroke
				(width 0.1)
				(type default)
			)
			(layer "F.Fab")
		)
		(fp_line
			(start -0.12065 -0.2794)
			(end 0.12065 -0.2794)
			(stroke
				(width 0.1)
				(type default)
			)
			(layer "F.Fab")
		)
		(fp_line
			(start -0.12065 -0.305054)
			(end -0.12065 -0.2794)
			(stroke
				(width 0.1)
				(type default)
			)
			(layer "F.Fab")
		)
		(fp_line
			(start -0.67945 0.3048)
			(end -0.67945 -0.305054)
			(stroke
				(width 0.1)
				(type default)
			)
			(layer "F.Fab")
		)
		(fp_line
			(start -0.67945 -0.305054)
			(end -0.12065 -0.305054)
			(stroke
				(width 0.1)
				(type default)
			)
			(layer "F.Fab")
		)
		(pad "1" smd circle
			(at -0.40005 0 180)
			(size 0 0)
			(layers "F.Cu" "F.Mask" "F.Paste")
			(net "PRSNTB0_NIC0_N")
		)
		(pad "2" smd circle
			(at 0.40005 0 180)
			(size 0 0)
			(layers "F.Cu" "F.Mask" "F.Paste")
			(net "P3V3_AUX")
		)
	)
)
